(kicad_pcb
	(version 20260206)
	(generator "pcbnew")
	(generator_version "10.0")
	(general
		(thickness 1.6)
		(legacy_teardrops no)
	)
	(paper "A4")
	(title_block
		(title "v1-chassis-manager — T6M_CM_d_v01_1031_1645.brd")
		(comment 1 "Open CloudServer (Microsoft) / footprints 944-953 of 2512")
	)
	(layers
		(0 "F.Cu" signal "TOP")
		(4 "In1.Cu" signal "GND1")
		(6 "In2.Cu" signal "IN1")
		(8 "In3.Cu" signal "VCC1")
		(10 "In4.Cu" signal "VCC2")
		(12 "In5.Cu" signal "GND2")
		(14 "In6.Cu" signal "IN2")
		(16 "In7.Cu" signal "IN3")
		(18 "In8.Cu" signal "GND3")
		(2 "B.Cu" signal "BOTTOM")
		(9 "F.Adhes" user "F.Adhesive")
		(11 "B.Adhes" user "B.Adhesive")
		(13 "F.Paste" user "Package Geometry/Pastemask Top")
		(15 "B.Paste" user "Package Geometry/Pastemask Bottom")
		(5 "F.SilkS" user "Ref Des/Silkscreen Top")
		(7 "B.SilkS" user "Ref Des/Silkscreen Bottom")
		(1 "F.Mask" user "Board Geometry/Soldermask Top")
		(3 "B.Mask" user "Board Geometry/Soldermask Bottom")
		(17 "Dwgs.User" user "User.Drawings")
		(19 "Cmts.User" user "User.Comments")
		(21 "Eco1.User" user "User.Eco1")
		(23 "Eco2.User" user "User.Eco2")
		(25 "Edge.Cuts" user "Board Geometry/Outline")
		(27 "Margin" user)
		(31 "F.CrtYd" user "Package Geometry/Place Bound Top")
		(29 "B.CrtYd" user "Package Geometry/Place Bound Bottom")
		(35 "F.Fab" user "Ref Des/Assembly Top")
		(33 "B.Fab" user "Ref Des/Assembly Bottom")
	)
	(footprint ""
		(layer "F.Cu")
		(at 72.82434 -100.89134 -90)
		(property "Reference" "R1231"
			(at -1.651 -0.538226 90)
			(unlocked yes)
			(layer "F.SilkS")
			(effects
				(font
					(size 0.7874 0.5842)
					(thickness 0.1524)
				)
				(justify left)
			)
		)
		(property "Value" ""
			(at 0 0 270)
			(layer "F.Fab")
			(effects
				(font
					(size 1.27 1.27)
				)
			)
		)
		(duplicate_pad_numbers_are_jumpers no)
		(fp_line
			(start -0.7874 0.4064)
			(end -0.7874 -0.4064)
			(stroke
				(width 0.1524)
				(type default)
			)
			(layer "F.SilkS")
		)
		(fp_line
			(start 0.7874 0.4064)
			(end -0.7874 0.4064)
			(stroke
				(width 0.1524)
				(type default)
			)
			(layer "F.SilkS")
		)
		(fp_line
			(start -0.7874 -0.4064)
			(end 0.7874 -0.4064)
			(stroke
				(width 0.1524)
				(type default)
			)
			(layer "F.SilkS")
		)
		(fp_line
			(start 0.7874 -0.4064)
			(end 0.7874 0.4064)
			(stroke
				(width 0.1524)
				(type default)
			)
			(layer "F.SilkS")
		)
		(fp_poly
			(pts
				(xy -0.508 0.2794) (xy -0.508 0.2286) (xy -0.635 0.2286) (xy -0.635 -0.254) (xy -0.5334 -0.254)
				(xy -0.5334 -0.2794) (xy 0.5334 -0.2794) (xy 0.5334 -0.254) (xy 0.635 -0.254) (xy 0.635 0.254) (xy 0.5334 0.254)
				(xy 0.5334 0.2794)
			)
			(stroke
				(width 0)
				(type default)
			)
			(fill no)
			(layer "F.CrtYd")
		)
		(pad "1" smd rect
			(at 0.40005 0 270)
			(size 0.4572 0.508)
			(layers "F.Cu" "F.Mask" "F.Paste")
			(net "GND")
		)
		(pad "2" smd rect
			(at -0.40005 0 270)
			(size 0.4572 0.508)
			(layers "F.Cu" "F.Mask" "F.Paste")
			(net "FM_CPLD_NODE1_P1V8_SUS_EN")
		)
	)
	(footprint ""
		(layer "F.Cu")
		(at 112.069118 -163.282122)
		(property "Reference" "R683"
			(at -2.115058 -12.402566 0)
			(unlocked yes)
			(layer "F.SilkS")
			(effects
				(font
					(size 0.7874 0.5842)
					(thickness 0.1524)
				)
				(justify left)
			)
		)
		(property "Value" ""
			(at 0 0 0)
			(layer "F.Fab")
			(effects
				(font
					(size 1.27 1.27)
				)
			)
		)
		(duplicate_pad_numbers_are_jumpers no)
		(fp_line
			(start -0.7874 -0.4064)
			(end 0.7874 -0.4064)
			(stroke
				(width 0.1524)
				(type default)
			)
			(layer "F.SilkS")
		)
		(fp_line
			(start -0.7874 0.4064)
			(end -0.7874 -0.4064)
			(stroke
				(width 0.1524)
				(type default)
			)
			(layer "F.SilkS")
		)
		(fp_line
			(start 0.7874 -0.4064)
			(end 0.7874 0.4064)
			(stroke
				(width 0.1524)
				(type default)
			)
			(layer "F.SilkS")
		)
		(fp_line
			(start 0.7874 0.4064)
			(end -0.7874 0.4064)
			(stroke
				(width 0.1524)
				(type default)
			)
			(layer "F.SilkS")
		)
		(fp_poly
			(pts
				(xy -0.508 0.2794) (xy -0.508 0.2286) (xy -0.635 0.2286) (xy -0.635 -0.254) (xy -0.5334 -0.254)
				(xy -0.5334 -0.2794) (xy 0.5334 -0.2794) (xy 0.5334 -0.254) (xy 0.635 -0.254) (xy 0.635 0.254) (xy 0.5334 0.254)
				(xy 0.5334 0.2794)
			)
			(stroke
				(width 0)
				(type default)
			)
			(fill no)
			(layer "F.CrtYd")
		)
		(pad "1" smd rect
			(at 0.40005 0)
			(size 0.4572 0.508)
			(layers "F.Cu" "F.Mask" "F.Paste")
			(net "I2C_COM3_SCL")
		)
		(pad "2" smd rect
			(at -0.40005 0)
			(size 0.4572 0.508)
			(layers "F.Cu" "F.Mask" "F.Paste")
			(net "I2C_PDB_SCL")
		)
	)
	(footprint ""
		(layer "F.Cu")
		(at 136.161272 -160.248854 90)
		(property "Reference" "C906"
			(at -109.162342 -62.754256 90)
			(unlocked yes)
			(layer "F.SilkS")
			(effects
				(font
					(size 0.7874 0.5842)
					(thickness 0.1524)
				)
				(justify left)
			)
		)
		(property "Value" ""
			(at 0 0 90)
			(layer "F.Fab")
			(effects
				(font
					(size 1.27 1.27)
				)
			)
		)
		(duplicate_pad_numbers_are_jumpers no)
		(fp_line
			(start 0.7874 -0.4064)
			(end 0.7874 0.4064)
			(stroke
				(width 0.1524)
				(type default)
			)
			(layer "F.SilkS")
		)
		(fp_line
			(start -0.7874 -0.4064)
			(end 0.7874 -0.4064)
			(stroke
				(width 0.1524)
				(type default)
			)
			(layer "F.SilkS")
		)
		(fp_line
			(start 0 0.381)
			(end 0 -0.381)
			(stroke
				(width 0.1524)
				(type default)
			)
			(layer "F.SilkS")
		)
		(fp_line
			(start 0.7874 0.4064)
			(end -0.7874 0.4064)
			(stroke
				(width 0.1524)
				(type default)
			)
			(layer "F.SilkS")
		)
		(fp_line
			(start -0.7874 0.4064)
			(end -0.7874 -0.4064)
			(stroke
				(width 0.1524)
				(type default)
			)
			(layer "F.SilkS")
		)
		(fp_poly
			(pts
				(xy -0.5334 0.254) (xy -0.635 0.254) (xy -0.635 0.2286) (xy -0.635 -0.254) (xy -0.5334 -0.254) (xy -0.5334 -0.2794)
				(xy 0.5334 -0.2794) (xy 0.5334 -0.254) (xy 0.635 -0.254) (xy 0.635 0.254) (xy 0.5334 0.254) (xy 0.5334 0.2794)
				(xy -0.508 0.2794) (xy -0.5334 0.2794)
			)
			(stroke
				(width 0)
				(type default)
			)
			(fill no)
			(layer "F.CrtYd")
		)
		(pad "1" smd rect
			(at 0.40005 0 90)
			(size 0.4572 0.508)
			(layers "F.Cu" "F.Mask" "F.Paste")
			(net "P3V3_NODE1")
		)
		(pad "2" smd rect
			(at -0.40005 0 90)
			(size 0.4572 0.508)
			(layers "F.Cu" "F.Mask" "F.Paste")
			(net "GND")
		)
	)
	(footprint ""
		(layer "F.Cu")
		(at 184.7596 -177.4952 180)
		(property "Reference" "R1312"
			(at -9.9568 -17.45107 0)
			(unlocked yes)
			(layer "F.SilkS")
			(effects
				(font
					(size 0.7874 0.5842)
					(thickness 0.1524)
				)
				(justify left)
			)
		)
		(property "Value" ""
			(at 0 0 180)
			(layer "F.Fab")
			(effects
				(font
					(size 1.27 1.27)
				)
			)
		)
		(duplicate_pad_numbers_are_jumpers no)
		(fp_line
			(start 0.7874 0.4064)
			(end -0.7874 0.4064)
			(stroke
				(width 0.1524)
				(type default)
			)
			(layer "F.SilkS")
		)
		(fp_line
			(start 0.7874 -0.4064)
			(end 0.7874 0.4064)
			(stroke
				(width 0.1524)
				(type default)
			)
			(layer "F.SilkS")
		)
		(fp_line
			(start -0.7874 0.4064)
			(end -0.7874 -0.4064)
			(stroke
				(width 0.1524)
				(type default)
			)
			(layer "F.SilkS")
		)
		(fp_line
			(start -0.7874 -0.4064)
			(end 0.7874 -0.4064)
			(stroke
				(width 0.1524)
				(type default)
			)
			(layer "F.SilkS")
		)
		(fp_poly
			(pts
				(xy -0.508 0.2794) (xy -0.508 0.2286) (xy -0.635 0.2286) (xy -0.635 -0.254) (xy -0.5334 -0.254)
				(xy -0.5334 -0.2794) (xy 0.5334 -0.2794) (xy 0.5334 -0.254) (xy 0.635 -0.254) (xy 0.635 0.254) (xy 0.5334 0.254)
				(xy 0.5334 0.2794)
			)
			(stroke
				(width 0)
				(type default)
			)
			(fill no)
			(layer "F.CrtYd")
		)
		(pad "1" smd rect
			(at 0.40005 0 180)
			(size 0.4572 0.508)
			(layers "F.Cu" "F.Mask" "F.Paste")
			(net "POWER_SW2_PWR_CTR_12V")
		)
		(pad "2" smd rect
			(at -0.40005 0 180)
			(size 0.4572 0.508)
			(layers "F.Cu" "F.Mask" "F.Paste")
			(net "POWER_SW2_PWR_CTR_12V_R")
		)
	)
	(footprint ""
		(layer "F.Cu")
		(at 92.716604 -83.324192 -90)
		(property "Reference" "R1215"
			(at 0.933704 0.991108 90)
			(unlocked yes)
			(layer "F.SilkS")
			(effects
				(font
					(size 0.7874 0.5842)
					(thickness 0.1524)
				)
				(justify left)
			)
		)
		(property "Value" ""
			(at 0 0 270)
			(layer "F.Fab")
			(effects
				(font
					(size 1.27 1.27)
				)
			)
		)
		(duplicate_pad_numbers_are_jumpers no)
		(fp_line
			(start -0.7874 0.4064)
			(end -0.7874 -0.4064)
			(stroke
				(width 0.1524)
				(type default)
			)
			(layer "F.SilkS")
		)
		(fp_line
			(start 0.7874 0.4064)
			(end -0.7874 0.4064)
			(stroke
				(width 0.1524)
				(type default)
			)
			(layer "F.SilkS")
		)
		(fp_line
			(start -0.7874 -0.4064)
			(end 0.7874 -0.4064)
			(stroke
				(width 0.1524)
				(type default)
			)
			(layer "F.SilkS")
		)
		(fp_line
			(start 0.7874 -0.4064)
			(end 0.7874 0.4064)
			(stroke
				(width 0.1524)
				(type default)
			)
			(layer "F.SilkS")
		)
		(fp_poly
			(pts
				(xy -0.508 0.2794) (xy -0.508 0.2286) (xy -0.635 0.2286) (xy -0.635 -0.254) (xy -0.5334 -0.254)
				(xy -0.5334 -0.2794) (xy 0.5334 -0.2794) (xy 0.5334 -0.254) (xy 0.635 -0.254) (xy 0.635 0.254) (xy 0.5334 0.254)
				(xy 0.5334 0.2794)
			)
			(stroke
				(width 0)
				(type default)
			)
			(fill no)
			(layer "F.CrtYd")
		)
		(pad "1" smd rect
			(at 0.40005 0 270)
			(size 0.4572 0.508)
			(layers "F.Cu" "F.Mask" "F.Paste")
			(net "N45787194")
		)
		(pad "2" smd rect
			(at -0.40005 0 270)
			(size 0.4572 0.508)
			(layers "F.Cu" "F.Mask" "F.Paste")
			(net "P1V05_NODE1")
		)
	)
	(footprint ""
		(layer "F.Cu")
		(at 166.100252 -93.84919 90)
		(property "Reference" "R532"
			(at -1.23317 -4.402328 90)
			(unlocked yes)
			(layer "F.SilkS")
			(effects
				(font
					(size 0.7874 0.5842)
					(thickness 0.1524)
				)
				(justify left)
			)
		)
		(property "Value" ""
			(at 0 0 90)
			(layer "F.Fab")
			(effects
				(font
					(size 1.27 1.27)
				)
			)
		)
		(duplicate_pad_numbers_are_jumpers no)
		(fp_line
			(start 0.7874 -0.4064)
			(end 0.7874 0.4064)
			(stroke
				(width 0.1524)
				(type default)
			)
			(layer "F.SilkS")
		)
		(fp_line
			(start -0.7874 -0.4064)
			(end 0.7874 -0.4064)
			(stroke
				(width 0.1524)
				(type default)
			)
			(layer "F.SilkS")
		)
		(fp_line
			(start 0.7874 0.4064)
			(end -0.7874 0.4064)
			(stroke
				(width 0.1524)
				(type default)
			)
			(layer "F.SilkS")
		)
		(fp_line
			(start -0.7874 0.4064)
			(end -0.7874 -0.4064)
			(stroke
				(width 0.1524)
				(type default)
			)
			(layer "F.SilkS")
		)
		(fp_poly
			(pts
				(xy -0.508 0.2794) (xy -0.508 0.2286) (xy -0.635 0.2286) (xy -0.635 -0.254) (xy -0.5334 -0.254)
				(xy -0.5334 -0.2794) (xy 0.5334 -0.2794) (xy 0.5334 -0.254) (xy 0.635 -0.254) (xy 0.635 0.254) (xy 0.5334 0.254)
				(xy 0.5334 0.2794)
			)
			(stroke
				(width 0)
				(type default)
			)
			(fill no)
			(layer "F.CrtYd")
		)
		(pad "1" smd rect
			(at 0.40005 0 90)
			(size 0.4572 0.508)
			(layers "F.Cu" "F.Mask" "F.Paste")
			(net "USB_OC_PU")
		)
		(pad "2" smd rect
			(at -0.40005 0 90)
			(size 0.4572 0.508)
			(layers "F.Cu" "F.Mask" "F.Paste")
			(net "P3V3_NODE1")
		)
	)
	(footprint ""
		(layer "F.Cu")
		(at 185.01233 -150.688548 180)
		(property "Reference" "C468"
			(at -3.137408 0.282956 0)
			(unlocked yes)
			(layer "F.SilkS")
			(effects
				(font
					(size 0.7874 0.5842)
					(thickness 0.1524)
				)
			)
		)
		(property "Value" ""
			(at 0 0 180)
			(layer "F.Fab")
			(effects
				(font
					(size 1.27 1.27)
				)
			)
		)
		(duplicate_pad_numbers_are_jumpers no)
		(fp_line
			(start 1.2954 0.5842)
			(end -1.2954 0.5842)
			(stroke
				(width 0.1524)
				(type default)
			)
			(layer "F.SilkS")
		)
		(fp_line
			(start 1.2954 -0.5842)
			(end 1.2954 0.5842)
			(stroke
				(width 0.1524)
				(type default)
			)
			(layer "F.SilkS")
		)
		(fp_line
			(start 0 -0.5842)
			(end 0 0.5842)
			(stroke
				(width 0.1524)
				(type default)
			)
			(layer "F.SilkS")
		)
		(fp_line
			(start -1.2954 0.5842)
			(end -1.2954 -0.5842)
			(stroke
				(width 0.1524)
				(type default)
			)
			(layer "F.SilkS")
		)
		(fp_line
			(start -1.2954 -0.5842)
			(end 1.2954 -0.5842)
			(stroke
				(width 0.1524)
				(type default)
			)
			(layer "F.SilkS")
		)
		(fp_poly
			(pts
				(xy 0.8636 -0.4572) (xy 0.8636 -0.3556) (xy 1.143 -0.3556) (xy 1.143 0.3556) (xy 0.8636 0.3556)
				(xy 0.8636 0.4572) (xy -0.8636 0.4572) (xy -0.8636 0.3556) (xy -1.143 0.3556) (xy -1.143 -0.3556)
				(xy -0.8636 -0.3556) (xy -0.8636 -0.4572)
			)
			(stroke
				(width 0)
				(type default)
			)
			(fill no)
			(layer "F.CrtYd")
		)
		(fp_line
			(start 0.884936 0.504952)
			(end -0.884936 0.504952)
			(stroke
				(width 0.1)
				(type default)
			)
			(layer "F.Fab")
		)
		(fp_line
			(start 0.884936 -0.504952)
			(end 0.884936 0.504952)
			(stroke
				(width 0.1)
				(type default)
			)
			(layer "F.Fab")
		)
		(fp_line
			(start -0.884936 0.504952)
			(end -0.884936 -0.504952)
			(stroke
				(width 0.1)
				(type default)
			)
			(layer "F.Fab")
		)
		(fp_line
			(start -0.884936 -0.504952)
			(end 0.884936 -0.504952)
			(stroke
				(width 0.1)
				(type default)
			)
			(layer "F.Fab")
		)
		(pad "1" smd rect
			(at 0.7366 0 270)
			(size 0.7112 0.8128)
			(layers "F.Cu" "F.Mask" "F.Paste")
			(net "LAN2_CTRL_P1V9_R")
		)
		(pad "2" smd rect
			(at -0.7366 0 270)
			(size 0.7112 0.8128)
			(layers "F.Cu" "F.Mask" "F.Paste")
			(net "P1V9_LAN2")
		)
	)
	(footprint ""
		(layer "F.Cu")
		(at 62.511686 -121.044462 -90)
		(property "Reference" "R336"
			(at 6.142736 -8.573516 90)
			(unlocked yes)
			(layer "F.SilkS")
			(effects
				(font
					(size 0.7874 0.5842)
					(thickness 0.1524)
				)
				(justify left)
			)
		)
		(property "Value" ""
			(at 0 0 270)
			(layer "F.Fab")
			(effects
				(font
					(size 1.27 1.27)
				)
			)
		)
		(duplicate_pad_numbers_are_jumpers no)
		(fp_line
			(start -0.7874 0.4064)
			(end -0.7874 -0.4064)
			(stroke
				(width 0.1524)
				(type default)
			)
			(layer "F.SilkS")
		)
		(fp_line
			(start 0.7874 0.4064)
			(end -0.7874 0.4064)
			(stroke
				(width 0.1524)
				(type default)
			)
			(layer "F.SilkS")
		)
		(fp_line
			(start -0.7874 -0.4064)
			(end 0.7874 -0.4064)
			(stroke
				(width 0.1524)
				(type default)
			)
			(layer "F.SilkS")
		)
		(fp_line
			(start 0.7874 -0.4064)
			(end 0.7874 0.4064)
			(stroke
				(width 0.1524)
				(type default)
			)
			(layer "F.SilkS")
		)
		(fp_poly
			(pts
				(xy -0.508 0.2794) (xy -0.508 0.2286) (xy -0.635 0.2286) (xy -0.635 -0.254) (xy -0.5334 -0.254)
				(xy -0.5334 -0.2794) (xy 0.5334 -0.2794) (xy 0.5334 -0.254) (xy 0.635 -0.254) (xy 0.635 0.254) (xy 0.5334 0.254)
				(xy 0.5334 0.2794)
			)
			(stroke
				(width 0)
				(type default)
			)
			(fill no)
			(layer "F.CrtYd")
		)
		(pad "1" smd rect
			(at 0.40005 0 270)
			(size 0.4572 0.508)
			(layers "F.Cu" "F.Mask" "F.Paste")
			(net "P3V3_NODE1")
		)
		(pad "2" smd rect
			(at -0.40005 0 270)
			(size 0.4572 0.508)
			(layers "F.Cu" "F.Mask" "F.Paste")
			(net "BMC_ROMA20")
		)
	)
	(footprint ""
		(layer "F.Cu")
		(at 33.173162 -107.26928 180)
		(property "Reference" "R1087"
			(at -1.528318 -0.703072 0)
			(unlocked yes)
			(layer "F.SilkS")
			(effects
				(font
					(size 0.7874 0.5842)
					(thickness 0.1524)
				)
				(justify left)
			)
		)
		(property "Value" ""
			(at 0 0 180)
			(layer "F.Fab")
			(effects
				(font
					(size 1.27 1.27)
				)
			)
		)
		(duplicate_pad_numbers_are_jumpers no)
		(fp_line
			(start 0.7874 0.4064)
			(end -0.7874 0.4064)
			(stroke
				(width 0.1524)
				(type default)
			)
			(layer "F.SilkS")
		)
		(fp_line
			(start 0.7874 -0.4064)
			(end 0.7874 0.4064)
			(stroke
				(width 0.1524)
				(type default)
			)
			(layer "F.SilkS")
		)
		(fp_line
			(start -0.7874 0.4064)
			(end -0.7874 -0.4064)
			(stroke
				(width 0.1524)
				(type default)
			)
			(layer "F.SilkS")
		)
		(fp_line
			(start -0.7874 -0.4064)
			(end 0.7874 -0.4064)
			(stroke
				(width 0.1524)
				(type default)
			)
			(layer "F.SilkS")
		)
		(fp_poly
			(pts
				(xy -0.508 0.2794) (xy -0.508 0.2286) (xy -0.635 0.2286) (xy -0.635 -0.254) (xy -0.5334 -0.254)
				(xy -0.5334 -0.2794) (xy 0.5334 -0.2794) (xy 0.5334 -0.254) (xy 0.635 -0.254) (xy 0.635 0.254) (xy 0.5334 0.254)
				(xy 0.5334 0.2794)
			)
			(stroke
				(width 0)
				(type default)
			)
			(fill no)
			(layer "F.CrtYd")
		)
		(pad "1" smd rect
			(at 0.40005 0 180)
			(size 0.4572 0.508)
			(layers "F.Cu" "F.Mask" "F.Paste")
			(net "P3V3_STB_NODE1")
		)
		(pad "2" smd rect
			(at -0.40005 0 180)
			(size 0.4572 0.508)
			(layers "F.Cu" "F.Mask" "F.Paste")
			(net "PWRGD_NODE1_P1V5_SUS_PG")
		)
	)
	(footprint ""
		(layer "F.Cu")
		(at 94.248986 -138.040618 180)
		(property "Reference" "R1086"
			(at 1.001014 4.063746 0)
			(unlocked yes)
			(layer "F.SilkS")
			(effects
				(font
					(size 0.7874 0.5842)
					(thickness 0.1524)
				)
				(justify left)
			)
		)
		(property "Value" ""
			(at 0 0 180)
			(layer "F.Fab")
			(effects
				(font
					(size 1.27 1.27)
				)
			)
		)
		(duplicate_pad_numbers_are_jumpers no)
		(fp_line
			(start 0.7874 0.4064)
			(end -0.7874 0.4064)
			(stroke
				(width 0.1524)
				(type default)
			)
			(layer "F.SilkS")
		)
		(fp_line
			(start 0.7874 -0.4064)
			(end 0.7874 0.4064)
			(stroke
				(width 0.1524)
				(type default)
			)
			(layer "F.SilkS")
		)
		(fp_line
			(start -0.7874 0.4064)
			(end -0.7874 -0.4064)
			(stroke
				(width 0.1524)
				(type default)
			)
			(layer "F.SilkS")
		)
		(fp_line
			(start -0.7874 -0.4064)
			(end 0.7874 -0.4064)
			(stroke
				(width 0.1524)
				(type default)
			)
			(layer "F.SilkS")
		)
		(fp_poly
			(pts
				(xy -0.508 0.2794) (xy -0.508 0.2286) (xy -0.635 0.2286) (xy -0.635 -0.254) (xy -0.5334 -0.254)
				(xy -0.5334 -0.2794) (xy 0.5334 -0.2794) (xy 0.5334 -0.254) (xy 0.635 -0.254) (xy 0.635 0.254) (xy 0.5334 0.254)
				(xy 0.5334 0.2794)
			)
			(stroke
				(width 0)
				(type default)
			)
			(fill no)
			(layer "F.CrtYd")
		)
		(pad "1" smd rect
			(at 0.40005 0 180)
			(size 0.4572 0.508)
			(layers "F.Cu" "F.Mask" "F.Paste")
			(net "GND")
		)
		(pad "2" smd rect
			(at -0.40005 0 180)
			(size 0.4572 0.508)
			(layers "F.Cu" "F.Mask" "F.Paste")
			(net "P1V05_SUS_NODE1_ADJ")
		)
	)
)
